(kicad_pcb
	(version 20260206)
	(generator "pcbnew")
	(generator_version "10.0")
	(general
		(thickness 1.6)
		(legacy_teardrops no)
	)
	(paper "A4")
	(title_block
		(title "01162023_DA0F0TEBIF0_F0T_Expander_BD_F_brd_V02_OCP.brd")
		(comment 1 "Grand Teton / footprints 4958-4964 of 9728")
	)
	(layers
		(0 "F.Cu" signal "TOP")
		(4 "In1.Cu" signal "GND")
		(6 "In2.Cu" signal "VCC")
		(8 "In3.Cu" signal "VCC1")
		(10 "In4.Cu" signal "GND1")
		(12 "In5.Cu" signal "IN1")
		(14 "In6.Cu" signal "GND2")
		(16 "In7.Cu" signal "IN2")
		(18 "In8.Cu" signal "GND3")
		(20 "In9.Cu" signal "IN3")
		(22 "In10.Cu" signal "GND4")
		(24 "In11.Cu" signal "IN4")
		(26 "In12.Cu" signal "GND5")
		(28 "In13.Cu" signal "IN5")
		(30 "In14.Cu" signal "GND6")
		(32 "In15.Cu" signal "IN6")
		(34 "In16.Cu" signal "GND7")
		(2 "B.Cu" signal "BOTTOM")
		(9 "F.Adhes" user "F.Adhesive")
		(11 "B.Adhes" user "B.Adhesive")
		(13 "F.Paste" user "Package Geometry/Pastemask Top")
		(15 "B.Paste" user "Package Geometry/Pastemask Bottom")
		(5 "F.SilkS" user "Ref Des/Silkscreen Top")
		(7 "B.SilkS" user "Ref Des/Silkscreen Bottom")
		(1 "F.Mask" user "Board Geometry/Soldermask Top")
		(3 "B.Mask" user "Board Geometry/Soldermask Bottom")
		(17 "Dwgs.User" user "User.Drawings")
		(19 "Cmts.User" user "User.Comments")
		(21 "Eco1.User" user "User.Eco1")
		(23 "Eco2.User" user "User.Eco2")
		(25 "Edge.Cuts" user "Board Geometry/Outline")
		(27 "Margin" user)
		(31 "F.CrtYd" user "Package Geometry/Place Bound Top")
		(29 "B.CrtYd" user "Package Geometry/Place Bound Bottom")
		(35 "F.Fab" user "Ref Des/Assembly Top")
		(33 "B.Fab" user "Ref Des/Assembly Bottom")
	)
	(footprint ""
		(layer "F.Cu")
		(at 355.913436 -135.058404 180)
		(property "Reference" "C2858"
			(at 0 0 180)
			(layer "F.SilkS")
			(hide yes)
			(effects
				(font
					(size 1.27 1.27)
				)
			)
		)
		(property "Value" ""
			(at 0 0 180)
			(layer "F.Fab")
			(effects
				(font
					(size 1.27 1.27)
				)
			)
		)
		(duplicate_pad_numbers_are_jumpers no)
		(fp_line
			(start 0.7874 0.4064)
			(end -0.7874 0.4064)
			(stroke
				(width 0.1524)
				(type default)
			)
			(layer "F.SilkS")
		)
		(fp_line
			(start 0.7874 -0.4064)
			(end 0.7874 0.4064)
			(stroke
				(width 0.1524)
				(type default)
			)
			(layer "F.SilkS")
		)
		(fp_line
			(start -0.7874 0.4064)
			(end -0.7874 -0.4064)
			(stroke
				(width 0.1524)
				(type default)
			)
			(layer "F.SilkS")
		)
		(fp_line
			(start -0.7874 -0.4064)
			(end 0.7874 -0.4064)
			(stroke
				(width 0.1524)
				(type default)
			)
			(layer "F.SilkS")
		)
		(fp_line
			(start 0.67945 0.3048)
			(end 0.120396 0.3048)
			(stroke
				(width 0.1)
				(type default)
			)
			(layer "F.Fab")
		)
		(fp_line
			(start 0.67945 -0.3048)
			(end 0.67945 0.3048)
			(stroke
				(width 0.1)
				(type default)
			)
			(layer "F.Fab")
		)
		(fp_line
			(start 0.12065 -0.2794)
			(end 0.12065 -0.3048)
			(stroke
				(width 0.1)
				(type default)
			)
			(layer "F.Fab")
		)
		(fp_line
			(start 0.12065 -0.3048)
			(end 0.67945 -0.3048)
			(stroke
				(width 0.1)
				(type default)
			)
			(layer "F.Fab")
		)
		(fp_line
			(start 0.120396 0.3048)
			(end 0.120396 0.2794)
			(stroke
				(width 0.1)
				(type default)
			)
			(layer "F.Fab")
		)
		(fp_line
			(start 0.120396 0.2794)
			(end -0.12065 0.2794)
			(stroke
				(width 0.1)
				(type default)
			)
			(layer "F.Fab")
		)
		(fp_line
			(start -0.12065 0.3048)
			(end -0.67945 0.3048)
			(stroke
				(width 0.1)
				(type default)
			)
			(layer "F.Fab")
		)
		(fp_line
			(start -0.12065 0.2794)
			(end -0.12065 0.3048)
			(stroke
				(width 0.1)
				(type default)
			)
			(layer "F.Fab")
		)
		(fp_line
			(start -0.12065 -0.2794)
			(end 0.12065 -0.2794)
			(stroke
				(width 0.1)
				(type default)
			)
			(layer "F.Fab")
		)
		(fp_line
			(start -0.12065 -0.305054)
			(end -0.12065 -0.2794)
			(stroke
				(width 0.1)
				(type default)
			)
			(layer "F.Fab")
		)
		(fp_line
			(start -0.67945 0.3048)
			(end -0.67945 -0.305054)
			(stroke
				(width 0.1)
				(type default)
			)
			(layer "F.Fab")
		)
		(fp_line
			(start -0.67945 -0.305054)
			(end -0.12065 -0.305054)
			(stroke
				(width 0.1)
				(type default)
			)
			(layer "F.Fab")
		)
		(pad "1" smd circle
			(at -0.40005 0 180)
			(size 0 0)
			(layers "F.Cu" "F.Mask" "F.Paste")
			(net "P12V_NIC6_EN_R")
		)
		(pad "2" smd circle
			(at 0.40005 0 180)
			(size 0 0)
			(layers "F.Cu" "F.Mask" "F.Paste")
			(net "GND")
		)
	)
	(footprint ""
		(layer "F.Cu")
		(at 275.004022 -343.952322 90)
		(property "Reference" "C2346"
			(at 0 0 90)
			(layer "F.SilkS")
			(hide yes)
			(effects
				(font
					(size 1.27 1.27)
				)
			)
		)
		(property "Value" ""
			(at 0 0 90)
			(layer "F.Fab")
			(effects
				(font
					(size 1.27 1.27)
				)
			)
		)
		(duplicate_pad_numbers_are_jumpers no)
		(fp_line
			(start 0.299974 -0.150114)
			(end 0.299974 0.150114)
			(stroke
				(width 0.1)
				(type default)
			)
			(layer "F.Fab")
		)
		(fp_line
			(start -0.299974 -0.150114)
			(end 0.299974 -0.150114)
			(stroke
				(width 0.1)
				(type default)
			)
			(layer "F.Fab")
		)
		(fp_line
			(start 0.299974 0.150114)
			(end -0.299974 0.150114)
			(stroke
				(width 0.1)
				(type default)
			)
			(layer "F.Fab")
		)
		(fp_line
			(start -0.299974 0.150114)
			(end -0.299974 -0.150114)
			(stroke
				(width 0.1)
				(type default)
			)
			(layer "F.Fab")
		)
		(pad "1" smd rect
			(at -0.2667 0 90)
			(size 0.3048 0.381)
			(layers "F.Cu" "F.Mask" "F.Paste")
			(net "P5E_PEX2_STN4_TX_DN<77>")
		)
		(pad "2" smd rect
			(at 0.2667 0 90)
			(size 0.3048 0.381)
			(layers "F.Cu" "F.Mask" "F.Paste")
			(net "P5E_PEX2_STN4_TX_C_DN<77>")
		)
	)
	(footprint ""
		(layer "F.Cu")
		(at 188.49721 -366.181386)
		(property "Reference" "PJ1"
			(at -1.013968 -4.913122 0)
			(unlocked yes)
			(layer "F.SilkS")
			(effects
				(font
					(size 0.7874 0.5842)
					(thickness 0.1524)
				)
				(justify left)
			)
		)
		(property "Value" ""
			(at 0 0 0)
			(layer "F.Fab")
			(effects
				(font
					(size 1.27 1.27)
				)
			)
		)
		(duplicate_pad_numbers_are_jumpers no)
		(fp_line
			(start -1.249934 -3.860038)
			(end -1.249934 -3.1877)
			(stroke
				(width 0.1524)
				(type default)
			)
			(layer "F.SilkS")
		)
		(fp_line
			(start -1.249934 -1.8923)
			(end -1.249934 1.8923)
			(stroke
				(width 0.1524)
				(type default)
			)
			(layer "F.SilkS")
		)
		(fp_line
			(start -1.249934 3.1877)
			(end -1.249934 3.860038)
			(stroke
				(width 0.1524)
				(type default)
			)
			(layer "F.SilkS")
		)
		(fp_line
			(start -1.249934 3.860038)
			(end 1.249934 3.860038)
			(stroke
				(width 0.1524)
				(type default)
			)
			(layer "F.SilkS")
		)
		(fp_line
			(start 1.249934 -3.860038)
			(end -1.249934 -3.860038)
			(stroke
				(width 0.1524)
				(type default)
			)
			(layer "F.SilkS")
		)
		(fp_line
			(start 1.249934 -0.6477)
			(end 1.249934 -3.860038)
			(stroke
				(width 0.1524)
				(type default)
			)
			(layer "F.SilkS")
		)
		(fp_line
			(start 1.249934 3.860038)
			(end 1.249934 0.6477)
			(stroke
				(width 0.1524)
				(type default)
			)
			(layer "F.SilkS")
		)
		(fp_poly
			(pts
				(xy -4.2164 -3.048) (xy -3.2004 -2.54) (xy -4.2164 -2.032)
			)
			(stroke
				(width 0)
				(type default)
			)
			(fill yes)
			(layer "F.SilkS")
		)
		(fp_line
			(start -1.249934 -3.860038)
			(end -1.249934 3.860038)
			(stroke
				(width 0.1)
				(type default)
			)
			(layer "F.Fab")
		)
		(fp_line
			(start -1.249934 3.860038)
			(end 1.249934 3.860038)
			(stroke
				(width 0.1)
				(type default)
			)
			(layer "F.Fab")
		)
		(fp_line
			(start 1.249934 -3.860038)
			(end -1.249934 -3.860038)
			(stroke
				(width 0.1)
				(type default)
			)
			(layer "F.Fab")
		)
		(fp_line
			(start 1.249934 3.860038)
			(end 1.249934 -3.860038)
			(stroke
				(width 0.1)
				(type default)
			)
			(layer "F.Fab")
		)
		(fp_poly
			(pts
				(xy -4.2164 -3.048) (xy -3.2004 -2.54) (xy -4.2164 -2.032)
			)
			(stroke
				(width 0)
				(type default)
			)
			(fill yes)
			(layer "F.Fab")
		)
		(pad "1" smd rect
			(at -1.374902 -2.54 270)
			(size 1.016 2.7686)
			(layers "F.Cu" "F.Mask" "F.Paste")
			(net "GND")
		)
		(pad "2" smd rect
			(at 1.374902 0 270)
			(size 1.016 2.7686)
			(layers "F.Cu" "F.Mask" "F.Paste")
			(net "SMB_HOTSWAP_SDA_R")
		)
		(pad "3" smd rect
			(at -1.374902 2.54 270)
			(size 1.016 2.7686)
			(layers "F.Cu" "F.Mask" "F.Paste")
			(net "SMB_HOTSWAP_SCL_R")
		)
	)
	(footprint ""
		(layer "F.Cu")
		(at 213.935056 -215.26246)
		(property "Reference" "R4880"
			(at 0 0 0)
			(layer "F.SilkS")
			(hide yes)
			(effects
				(font
					(size 1.27 1.27)
				)
			)
		)
		(property "Value" ""
			(at 0 0 0)
			(layer "F.Fab")
			(effects
				(font
					(size 1.27 1.27)
				)
			)
		)
		(duplicate_pad_numbers_are_jumpers no)
		(fp_line
			(start -0.7874 -0.4064)
			(end 0.7874 -0.4064)
			(stroke
				(width 0.1524)
				(type default)
			)
			(layer "F.SilkS")
		)
		(fp_line
			(start -0.7874 0.4064)
			(end -0.7874 -0.4064)
			(stroke
				(width 0.1524)
				(type default)
			)
			(layer "F.SilkS")
		)
		(fp_line
			(start 0.7874 -0.4064)
			(end 0.7874 0.4064)
			(stroke
				(width 0.1524)
				(type default)
			)
			(layer "F.SilkS")
		)
		(fp_line
			(start 0.7874 0.4064)
			(end -0.7874 0.4064)
			(stroke
				(width 0.1524)
				(type default)
			)
			(layer "F.SilkS")
		)
		(fp_line
			(start -0.67945 -0.305054)
			(end -0.12065 -0.305054)
			(stroke
				(width 0.1)
				(type default)
			)
			(layer "F.Fab")
		)
		(fp_line
			(start -0.67945 0.3048)
			(end -0.67945 -0.305054)
			(stroke
				(width 0.1)
				(type default)
			)
			(layer "F.Fab")
		)
		(fp_line
			(start -0.12065 -0.305054)
			(end -0.12065 -0.2794)
			(stroke
				(width 0.1)
				(type default)
			)
			(layer "F.Fab")
		)
		(fp_line
			(start -0.12065 -0.2794)
			(end 0.12065 -0.2794)
			(stroke
				(width 0.1)
				(type default)
			)
			(layer "F.Fab")
		)
		(fp_line
			(start -0.12065 0.2794)
			(end -0.12065 0.3048)
			(stroke
				(width 0.1)
				(type default)
			)
			(layer "F.Fab")
		)
		(fp_line
			(start -0.12065 0.3048)
			(end -0.67945 0.3048)
			(stroke
				(width 0.1)
				(type default)
			)
			(layer "F.Fab")
		)
		(fp_line
			(start 0.120396 0.2794)
			(end -0.12065 0.2794)
			(stroke
				(width 0.1)
				(type default)
			)
			(layer "F.Fab")
		)
		(fp_line
			(start 0.120396 0.3048)
			(end 0.120396 0.2794)
			(stroke
				(width 0.1)
				(type default)
			)
			(layer "F.Fab")
		)
		(fp_line
			(start 0.12065 -0.3048)
			(end 0.67945 -0.3048)
			(stroke
				(width 0.1)
				(type default)
			)
			(layer "F.Fab")
		)
		(fp_line
			(start 0.12065 -0.2794)
			(end 0.12065 -0.3048)
			(stroke
				(width 0.1)
				(type default)
			)
			(layer "F.Fab")
		)
		(fp_line
			(start 0.67945 -0.3048)
			(end 0.67945 0.3048)
			(stroke
				(width 0.1)
				(type default)
			)
			(layer "F.Fab")
		)
		(fp_line
			(start 0.67945 0.3048)
			(end 0.120396 0.3048)
			(stroke
				(width 0.1)
				(type default)
			)
			(layer "F.Fab")
		)
		(pad "1" smd circle
			(at -0.40005 0)
			(size 0 0)
			(layers "F.Cu" "F.Mask" "F.Paste")
			(net "P1V2_AUX")
		)
		(pad "2" smd circle
			(at 0.40005 0)
			(size 0 0)
			(layers "F.Cu" "F.Mask" "F.Paste")
			(net "SMB_NIC7_SDA")
		)
	)
	(footprint ""
		(layer "F.Cu")
		(at 252.842522 -179.167282)
		(property "Reference" "J19"
			(at -1.4224 -4.562348 0)
			(unlocked yes)
			(layer "F.SilkS")
			(effects
				(font
					(size 0.7874 0.5842)
					(thickness 0.1524)
				)
				(justify left)
			)
		)
		(property "Value" ""
			(at 0 0 0)
			(layer "F.Fab")
			(effects
				(font
					(size 1.27 1.27)
				)
			)
		)
		(duplicate_pad_numbers_are_jumpers no)
		(fp_line
			(start -1.27 -3.81)
			(end 1.27 -3.81)
			(stroke
				(width 0.1524)
				(type default)
			)
			(layer "F.SilkS")
		)
		(fp_line
			(start -1.27 -0.7747)
			(end -1.27 -3.81)
			(stroke
				(width 0.1524)
				(type default)
			)
			(layer "F.SilkS")
		)
		(fp_line
			(start -1.27 3.81)
			(end -1.27 0.7747)
			(stroke
				(width 0.1524)
				(type default)
			)
			(layer "F.SilkS")
		)
		(fp_line
			(start 1.27 -3.81)
			(end 1.27 -3.3147)
			(stroke
				(width 0.1524)
				(type default)
			)
			(layer "F.SilkS")
		)
		(fp_line
			(start 1.27 -1.7653)
			(end 1.27 1.7653)
			(stroke
				(width 0.1524)
				(type default)
			)
			(layer "F.SilkS")
		)
		(fp_line
			(start 1.27 3.3147)
			(end 1.27 3.81)
			(stroke
				(width 0.1524)
				(type default)
			)
			(layer "F.SilkS")
		)
		(fp_line
			(start 1.27 3.81)
			(end -1.27 3.81)
			(stroke
				(width 0.1524)
				(type default)
			)
			(layer "F.SilkS")
		)
		(fp_poly
			(pts
				(xy 4.3942 -3.048) (xy 4.3942 -2.032) (xy 3.3782 -2.54)
			)
			(stroke
				(width 0)
				(type default)
			)
			(fill yes)
			(layer "F.SilkS")
		)
		(fp_line
			(start -1.27 -3.81)
			(end -1.27 3.81)
			(stroke
				(width 0.1)
				(type default)
			)
			(layer "F.Fab")
		)
		(fp_line
			(start -1.27 3.81)
			(end 1.27 3.81)
			(stroke
				(width 0.1)
				(type default)
			)
			(layer "F.Fab")
		)
		(fp_line
			(start 1.27 -3.81)
			(end -1.27 -3.81)
			(stroke
				(width 0.1)
				(type default)
			)
			(layer "F.Fab")
		)
		(fp_line
			(start 1.27 3.81)
			(end 1.27 -3.81)
			(stroke
				(width 0.1)
				(type default)
			)
			(layer "F.Fab")
		)
		(fp_poly
			(pts
				(xy 4.3942 -3.048) (xy 4.3942 -2.032) (xy 3.3782 -2.54)
			)
			(stroke
				(width 0)
				(type default)
			)
			(fill yes)
			(layer "F.Fab")
		)
		(fp_text user "3"
			(at 3.921252 2.54 90)
			(unlocked yes)
			(layer "F.SilkS")
			(effects
				(font
					(size 0.7874 0.5842)
					(thickness 0.1524)
				)
			)
		)
		(fp_text user "3"
			(at 3.921252 2.54 90)
			(unlocked yes)
			(layer "F.Fab")
			(effects
				(font
					(size 0.7874 0.5842)
					(thickness 0.1524)
				)
			)
		)
		(pad "1" smd rect
			(at 1.459992 -2.54 90)
			(size 1.27 3.429)
			(layers "F.Cu" "F.Mask" "F.Paste")
			(net "Net_467")
		)
		(pad "2" smd rect
			(at -1.459992 0 90)
			(size 1.27 3.429)
			(layers "F.Cu" "F.Mask" "F.Paste")
			(net "BIC_FWSPICK")
		)
		(pad "3" smd rect
			(at 1.459992 2.54 90)
			(size 1.27 3.429)
			(layers "F.Cu" "F.Mask" "F.Paste")
			(net "BIC_FWSPICK_R")
		)
	)
	(footprint ""
		(layer "F.Cu")
		(at 314.083446 -61.487812 180)
		(property "Reference" "R6005"
			(at 0 0 180)
			(layer "F.SilkS")
			(hide yes)
			(effects
				(font
					(size 1.27 1.27)
				)
			)
		)
		(property "Value" ""
			(at 0 0 180)
			(layer "F.Fab")
			(effects
				(font
					(size 1.27 1.27)
				)
			)
		)
		(duplicate_pad_numbers_are_jumpers no)
		(fp_line
			(start 0.7874 0.4064)
			(end -0.7874 0.4064)
			(stroke
				(width 0.1524)
				(type default)
			)
			(layer "F.SilkS")
		)
		(fp_line
			(start 0.7874 -0.4064)
			(end 0.7874 0.4064)
			(stroke
				(width 0.1524)
				(type default)
			)
			(layer "F.SilkS")
		)
		(fp_line
			(start -0.7874 0.4064)
			(end -0.7874 -0.4064)
			(stroke
				(width 0.1524)
				(type default)
			)
			(layer "F.SilkS")
		)
		(fp_line
			(start -0.7874 -0.4064)
			(end 0.7874 -0.4064)
			(stroke
				(width 0.1524)
				(type default)
			)
			(layer "F.SilkS")
		)
		(fp_line
			(start 0.67945 0.3048)
			(end 0.120396 0.3048)
			(stroke
				(width 0.1)
				(type default)
			)
			(layer "F.Fab")
		)
		(fp_line
			(start 0.67945 -0.3048)
			(end 0.67945 0.3048)
			(stroke
				(width 0.1)
				(type default)
			)
			(layer "F.Fab")
		)
		(fp_line
			(start 0.12065 -0.2794)
			(end 0.12065 -0.3048)
			(stroke
				(width 0.1)
				(type default)
			)
			(layer "F.Fab")
		)
		(fp_line
			(start 0.12065 -0.3048)
			(end 0.67945 -0.3048)
			(stroke
				(width 0.1)
				(type default)
			)
			(layer "F.Fab")
		)
		(fp_line
			(start 0.120396 0.3048)
			(end 0.120396 0.2794)
			(stroke
				(width 0.1)
				(type default)
			)
			(layer "F.Fab")
		)
		(fp_line
			(start 0.120396 0.2794)
			(end -0.12065 0.2794)
			(stroke
				(width 0.1)
				(type default)
			)
			(layer "F.Fab")
		)
		(fp_line
			(start -0.12065 0.3048)
			(end -0.67945 0.3048)
			(stroke
				(width 0.1)
				(type default)
			)
			(layer "F.Fab")
		)
		(fp_line
			(start -0.12065 0.2794)
			(end -0.12065 0.3048)
			(stroke
				(width 0.1)
				(type default)
			)
			(layer "F.Fab")
		)
		(fp_line
			(start -0.12065 -0.2794)
			(end 0.12065 -0.2794)
			(stroke
				(width 0.1)
				(type default)
			)
			(layer "F.Fab")
		)
		(fp_line
			(start -0.12065 -0.305054)
			(end -0.12065 -0.2794)
			(stroke
				(width 0.1)
				(type default)
			)
			(layer "F.Fab")
		)
		(fp_line
			(start -0.67945 0.3048)
			(end -0.67945 -0.305054)
			(stroke
				(width 0.1)
				(type default)
			)
			(layer "F.Fab")
		)
		(fp_line
			(start -0.67945 -0.305054)
			(end -0.12065 -0.305054)
			(stroke
				(width 0.1)
				(type default)
			)
			(layer "F.Fab")
		)
		(pad "1" smd circle
			(at -0.40005 0 180)
			(size 0 0)
			(layers "F.Cu" "F.Mask" "F.Paste")
			(net "PWRGD_P12V_SSD11_D")
		)
		(pad "2" smd circle
			(at 0.40005 0 180)
			(size 0 0)
			(layers "F.Cu" "F.Mask" "F.Paste")
			(net "PWRGD_P12V_SSD11_R")
		)
	)
	(footprint ""
		(layer "F.Cu")
		(at 381.254 -197.358)
		(property "Reference" "R4665"
			(at 0 0 0)
			(layer "F.SilkS")
			(hide yes)
			(effects
				(font
					(size 1.27 1.27)
				)
			)
		)
		(property "Value" ""
			(at 0 0 0)
			(layer "F.Fab")
			(effects
				(font
					(size 1.27 1.27)
				)
			)
		)
		(duplicate_pad_numbers_are_jumpers no)
		(fp_line
			(start -0.7874 -0.4064)
			(end 0.7874 -0.4064)
			(stroke
				(width 0.1524)
				(type default)
			)
			(layer "F.SilkS")
		)
		(fp_line
			(start -0.7874 0.4064)
			(end -0.7874 -0.4064)
			(stroke
				(width 0.1524)
				(type default)
			)
			(layer "F.SilkS")
		)
		(fp_line
			(start 0.7874 -0.4064)
			(end 0.7874 0.4064)
			(stroke
				(width 0.1524)
				(type default)
			)
			(layer "F.SilkS")
		)
		(fp_line
			(start 0.7874 0.4064)
			(end -0.7874 0.4064)
			(stroke
				(width 0.1524)
				(type default)
			)
			(layer "F.SilkS")
		)
		(fp_line
			(start -0.67945 -0.305054)
			(end -0.12065 -0.305054)
			(stroke
				(width 0.1)
				(type default)
			)
			(layer "F.Fab")
		)
		(fp_line
			(start -0.67945 0.3048)
			(end -0.67945 -0.305054)
			(stroke
				(width 0.1)
				(type default)
			)
			(layer "F.Fab")
		)
		(fp_line
			(start -0.12065 -0.305054)
			(end -0.12065 -0.2794)
			(stroke
				(width 0.1)
				(type default)
			)
			(layer "F.Fab")
		)
		(fp_line
			(start -0.12065 -0.2794)
			(end 0.12065 -0.2794)
			(stroke
				(width 0.1)
				(type default)
			)
			(layer "F.Fab")
		)
		(fp_line
			(start -0.12065 0.2794)
			(end -0.12065 0.3048)
			(stroke
				(width 0.1)
				(type default)
			)
			(layer "F.Fab")
		)
		(fp_line
			(start -0.12065 0.3048)
			(end -0.67945 0.3048)
			(stroke
				(width 0.1)
				(type default)
			)
			(layer "F.Fab")
		)
		(fp_line
			(start 0.120396 0.2794)
			(end -0.12065 0.2794)
			(stroke
				(width 0.1)
				(type default)
			)
			(layer "F.Fab")
		)
		(fp_line
			(start 0.120396 0.3048)
			(end 0.120396 0.2794)
			(stroke
				(width 0.1)
				(type default)
			)
			(layer "F.Fab")
		)
		(fp_line
			(start 0.12065 -0.3048)
			(end 0.67945 -0.3048)
			(stroke
				(width 0.1)
				(type default)
			)
			(layer "F.Fab")
		)
		(fp_line
			(start 0.12065 -0.2794)
			(end 0.12065 -0.3048)
			(stroke
				(width 0.1)
				(type default)
			)
			(layer "F.Fab")
		)
		(fp_line
			(start 0.67945 -0.3048)
			(end 0.67945 0.3048)
			(stroke
				(width 0.1)
				(type default)
			)
			(layer "F.Fab")
		)
		(fp_line
			(start 0.67945 0.3048)
			(end 0.120396 0.3048)
			(stroke
				(width 0.1)
				(type default)
			)
			(layer "F.Fab")
		)
		(pad "1" smd circle
			(at -0.40005 0)
			(size 0 0)
			(layers "F.Cu" "F.Mask" "F.Paste")
			(net "P3V3_AUX")
		)
		(pad "2" smd circle
			(at 0.40005 0)
			(size 0 0)
			(layers "F.Cu" "F.Mask" "F.Paste")
			(net "NIC2_PEX_PWR_EN_R")
		)
	)
)
